# T6G (Grand Teton) — schematic netlist excerpt (pin names and nets, part order shuffled) for the footprints in the layout excerpt that follows; sources: Cadence DE-HDL packaged netlist, KiCad conversion of 04192023_DAF0TMB3IC0_F0TG_MB_C_brd_V02_OCP.brd

C2594  Q_CAP  22UF 4V 20% X6S  pkg C0402  page 70 : A = PVDDCR_SOC_P0 ; B = GND
C13  Q_CAP  0.1UF 25V 10% X7R  pkg 0402  page 125 : A = PRSNT_CABLE_GPU_B3_ISO_N ; B = GND
PC158_1  Q_CAP  22UF 16V 20% X6S  pkg C0805  page 205 : A = SW_P12V_AUX_PVDDIO_P0_FLT ; B = GND

(kicad_pcb
	(version 20260206)
	(generator "pcbnew")
	(generator_version "10.0")
	(general
		(thickness 1.6)
		(legacy_teardrops no)
	)
	(paper "A4")
	(title_block
		(title "04192023_DAF0TMB3IC0_F0TG_MB_C_brd_V02_OCP.brd")
		(comment 1 "Grand Teton / footprints 6393-6395 of 8354")
	)
	(layers
		(0 "F.Cu" signal "TOP")
		(4 "In1.Cu" signal "GND")
		(6 "In2.Cu" signal "IN1")
		(8 "In3.Cu" signal "GND1")
		(10 "In4.Cu" signal "IN2")
		(12 "In5.Cu" signal "GND2")
		(14 "In6.Cu" signal "IN3")
		(16 "In7.Cu" signal "GND3")
		(18 "In8.Cu" signal "VCC")
		(20 "In9.Cu" signal "VCC1")
		(22 "In10.Cu" signal "GND4")
		(24 "In11.Cu" signal "IN4")
		(26 "In12.Cu" signal "GND5")
		(28 "In13.Cu" signal "IN5")
		(30 "In14.Cu" signal "GND6")
		(32 "In15.Cu" signal "IN6")
		(34 "In16.Cu" signal "GND7")
		(2 "B.Cu" signal "BOTTOM")
		(9 "F.Adhes" user "F.Adhesive")
		(11 "B.Adhes" user "B.Adhesive")
		(13 "F.Paste" user "Package Geometry/Pastemask Top")
		(15 "B.Paste" user "Package Geometry/Pastemask Bottom")
		(5 "F.SilkS" user "Ref Des/Silkscreen Top")
		(7 "B.SilkS" user "Ref Des/Silkscreen Bottom")
		(1 "F.Mask" user "Board Geometry/Soldermask Top")
		(3 "B.Mask" user "Board Geometry/Soldermask Bottom")
		(17 "Dwgs.User" user "User.Drawings")
		(19 "Cmts.User" user "User.Comments")
		(21 "Eco1.User" user "User.Eco1")
		(23 "Eco2.User" user "User.Eco2")
		(25 "Edge.Cuts" user "Board Geometry/Outline")
		(27 "Margin" user)
		(31 "F.CrtYd" user "Package Geometry/Place Bound Top")
		(29 "B.CrtYd" user "Package Geometry/Place Bound Bottom")
		(35 "F.Fab" user "Ref Des/Assembly Top")
		(33 "B.Fab" user "Ref Des/Assembly Bottom")
	)
	(footprint ""
		(layer "B.Cu")
		(at 365.835692 -261.255002)
		(property "Reference" "C2594"
			(at 0 0 0)
			(layer "B.SilkS")
			(hide yes)
			(effects
				(font
					(size 1.27 1.27)
				)
				(justify mirror)
			)
		)
		(property "Value" ""
			(at 0 0 0)
			(layer "B.Fab")
			(effects
				(font
					(size 1.27 1.27)
				)
				(justify mirror)
			)
		)
		(duplicate_pad_numbers_are_jumpers no)
		(fp_line
			(start -0.7874 -0.4064)
			(end -0.7874 0.4064)
			(stroke
				(width 0.1524)
				(type default)
			)
			(layer "B.SilkS")
		)
		(fp_line
			(start -0.7874 0.4064)
			(end 0.7874 0.4064)
			(stroke
				(width 0.1524)
				(type default)
			)
			(layer "B.SilkS")
		)
		(fp_line
			(start 0.7874 -0.4064)
			(end -0.7874 -0.4064)
			(stroke
				(width 0.1524)
				(type default)
			)
			(layer "B.SilkS")
		)
		(fp_line
			(start 0.7874 0.4064)
			(end 0.7874 -0.4064)
			(stroke
				(width 0.1524)
				(type default)
			)
			(layer "B.SilkS")
		)
		(fp_line
			(start -0.67945 -0.3048)
			(end -0.67945 0.3048)
			(stroke
				(width 0.1)
				(type default)
			)
			(layer "B.Fab")
		)
		(fp_line
			(start -0.67945 0.3048)
			(end -0.120396 0.3048)
			(stroke
				(width 0.1)
				(type default)
			)
			(layer "B.Fab")
		)
		(fp_line
			(start -0.12065 -0.3048)
			(end -0.67945 -0.3048)
			(stroke
				(width 0.1)
				(type default)
			)
			(layer "B.Fab")
		)
		(fp_line
			(start -0.12065 -0.2794)
			(end -0.12065 -0.3048)
			(stroke
				(width 0.1)
				(type default)
			)
			(layer "B.Fab")
		)
		(fp_line
			(start -0.120396 0.2794)
			(end 0.12065 0.2794)
			(stroke
				(width 0.1)
				(type default)
			)
			(layer "B.Fab")
		)
		(fp_line
			(start -0.120396 0.3048)
			(end -0.120396 0.2794)
			(stroke
				(width 0.1)
				(type default)
			)
			(layer "B.Fab")
		)
		(fp_line
			(start 0.12065 -0.305054)
			(end 0.12065 -0.2794)
			(stroke
				(width 0.1)
				(type default)
			)
			(layer "B.Fab")
		)
		(fp_line
			(start 0.12065 -0.2794)
			(end -0.12065 -0.2794)
			(stroke
				(width 0.1)
				(type default)
			)
			(layer "B.Fab")
		)
		(fp_line
			(start 0.12065 0.2794)
			(end 0.12065 0.3048)
			(stroke
				(width 0.1)
				(type default)
			)
			(layer "B.Fab")
		)
		(fp_line
			(start 0.12065 0.3048)
			(end 0.67945 0.3048)
			(stroke
				(width 0.1)
				(type default)
			)
			(layer "B.Fab")
		)
		(fp_line
			(start 0.67945 -0.305054)
			(end 0.12065 -0.305054)
			(stroke
				(width 0.1)
				(type default)
			)
			(layer "B.Fab")
		)
		(fp_line
			(start 0.67945 0.3048)
			(end 0.67945 -0.305054)
			(stroke
				(width 0.1)
				(type default)
			)
			(layer "B.Fab")
		)
		(pad "1" smd circle
			(at 0.40005 0 180)
			(size 0 0)
			(layers "B.Cu" "B.Mask" "B.Paste")
			(net "PVDDCR_SOC_P0")
		)
		(pad "2" smd circle
			(at -0.40005 0 180)
			(size 0 0)
			(layers "B.Cu" "B.Mask" "B.Paste")
			(net "GND")
		)
	)
	(footprint ""
		(layer "B.Cu")
		(at 303.614582 -346.784168 90)
		(property "Reference" "PC158_1"
			(at 0 0 90)
			(layer "B.SilkS")
			(hide yes)
			(effects
				(font
					(size 1.27 1.27)
				)
				(justify mirror)
			)
		)
		(property "Value" ""
			(at 0 0 90)
			(layer "B.Fab")
			(effects
				(font
					(size 1.27 1.27)
				)
				(justify mirror)
			)
		)
		(duplicate_pad_numbers_are_jumpers no)
		(fp_line
			(start 1.524 -0.762)
			(end -1.524 -0.762)
			(stroke
				(width 0.1524)
				(type default)
			)
			(layer "B.SilkS")
		)
		(fp_line
			(start -1.524 -0.762)
			(end -1.524 0.762)
			(stroke
				(width 0.1524)
				(type default)
			)
			(layer "B.SilkS")
		)
		(fp_line
			(start 1.524 0.762)
			(end 1.524 -0.762)
			(stroke
				(width 0.1524)
				(type default)
			)
			(layer "B.SilkS")
		)
		(fp_line
			(start -1.524 0.762)
			(end 1.524 0.762)
			(stroke
				(width 0.1524)
				(type default)
			)
			(layer "B.SilkS")
		)
		(fp_line
			(start 1.1049 -0.724916)
			(end 1.1049 0.724916)
			(stroke
				(width 0.1)
				(type default)
			)
			(layer "B.Fab")
		)
		(fp_line
			(start -1.1049 -0.724916)
			(end 1.1049 -0.724916)
			(stroke
				(width 0.1)
				(type default)
			)
			(layer "B.Fab")
		)
		(fp_line
			(start 1.1049 0.724916)
			(end -1.1049 0.724916)
			(stroke
				(width 0.1)
				(type default)
			)
			(layer "B.Fab")
		)
		(fp_line
			(start -1.1049 0.724916)
			(end -1.1049 -0.724916)
			(stroke
				(width 0.1)
				(type default)
			)
			(layer "B.Fab")
		)
		(pad "1" smd rect
			(at 0.889 0 90)
			(size 1.016 1.27)
			(layers "B.Cu" "B.Mask" "B.Paste")
			(net "SW_P12V_AUX_PVDDIO_P0_FLT")
		)
		(pad "2" smd rect
			(at -0.889 0 90)
			(size 1.016 1.27)
			(layers "B.Cu" "B.Mask" "B.Paste")
			(net "GND")
		)
	)
	(footprint ""
		(layer "B.Cu")
		(at 164.403532 -435.93258 -90)
		(property "Reference" "C13"
			(at 0 0 90)
			(layer "B.SilkS")
			(hide yes)
			(effects
				(font
					(size 1.27 1.27)
				)
				(justify mirror)
			)
		)
		(property "Value" ""
			(at 0 0 90)
			(layer "B.Fab")
			(effects
				(font
					(size 1.27 1.27)
				)
				(justify mirror)
			)
		)
		(duplicate_pad_numbers_are_jumpers no)
		(fp_line
			(start -0.7874 0.4064)
			(end 0.7874 0.4064)
			(stroke
				(width 0.1524)
				(type default)
			)
			(layer "B.SilkS")
		)
		(fp_line
			(start 0.7874 0.4064)
			(end 0.7874 -0.4064)
			(stroke
				(width 0.1524)
				(type default)
			)
			(layer "B.SilkS")
		)
		(fp_line
			(start -0.7874 -0.4064)
			(end -0.7874 0.4064)
			(stroke
				(width 0.1524)
				(type default)
			)
			(layer "B.SilkS")
		)
		(fp_line
			(start 0.7874 -0.4064)
			(end -0.7874 -0.4064)
			(stroke
				(width 0.1524)
				(type default)
			)
			(layer "B.SilkS")
		)
		(fp_line
			(start -0.67945 0.3048)
			(end -0.120396 0.3048)
			(stroke
				(width 0.1)
				(type default)
			)
			(layer "B.Fab")
		)
		(fp_line
			(start -0.120396 0.3048)
			(end -0.120396 0.2794)
			(stroke
				(width 0.1)
				(type default)
			)
			(layer "B.Fab")
		)
		(fp_line
			(start 0.12065 0.3048)
			(end 0.67945 0.3048)
			(stroke
				(width 0.1)
				(type default)
			)
			(layer "B.Fab")
		)
		(fp_line
			(start 0.67945 0.3048)
			(end 0.67945 -0.305054)
			(stroke
				(width 0.1)
				(type default)
			)
			(layer "B.Fab")
		)
		(fp_line
			(start -0.120396 0.2794)
			(end 0.12065 0.2794)
			(stroke
				(width 0.1)
				(type default)
			)
			(layer "B.Fab")
		)
		(fp_line
			(start 0.12065 0.2794)
			(end 0.12065 0.3048)
			(stroke
				(width 0.1)
				(type default)
			)
			(layer "B.Fab")
		)
		(fp_line
			(start -0.12065 -0.2794)
			(end -0.12065 -0.3048)
			(stroke
				(width 0.1)
				(type default)
			)
			(layer "B.Fab")
		)
		(fp_line
			(start 0.12065 -0.2794)
			(end -0.12065 -0.2794)
			(stroke
				(width 0.1)
				(type default)
			)
			(layer "B.Fab")
		)
		(fp_line
			(start -0.67945 -0.3048)
			(end -0.67945 0.3048)
			(stroke
				(width 0.1)
				(type default)
			)
			(layer "B.Fab")
		)
		(fp_line
			(start -0.12065 -0.3048)
			(end -0.67945 -0.3048)
			(stroke
				(width 0.1)
				(type default)
			)
			(layer "B.Fab")
		)
		(fp_line
			(start 0.12065 -0.305054)
			(end 0.12065 -0.2794)
			(stroke
				(width 0.1)
				(type default)
			)
			(layer "B.Fab")
		)
		(fp_line
			(start 0.67945 -0.305054)
			(end 0.12065 -0.305054)
			(stroke
				(width 0.1)
				(type default)
			)
			(layer "B.Fab")
		)
		(pad "1" smd circle
			(at 0.40005 0 90)
			(size 0 0)
			(layers "B.Cu" "B.Mask" "B.Paste")
			(net "PRSNT_CABLE_GPU_B3_ISO_N")
		)
		(pad "2" smd circle
			(at -0.40005 0 90)
			(size 0 0)
			(layers "B.Cu" "B.Mask" "B.Paste")
			(net "GND")
		)
	)
)
